(kicad_pcb
	(version 20241229)
	(generator "pcbnew")
	(generator_version "9.0")
	(general
		(thickness 1.6642)
		(legacy_teardrops no)
	)
	(paper "A3")
	(title_block
		(title "PolarFire SoM")
		(date "2025-07-22")
		(rev "1.1.4")
		(company "Antmicro Ltd")
		(comment 1 "www.antmicro.com")
		(comment 9 "footprint 74 of 470 (U12), pads 83-167 of 200")
	)
	(layers
		(0 "F.Cu" mixed)
		(4 "In1.Cu" power)
		(6 "In2.Cu" signal)
		(8 "In3.Cu" power)
		(10 "In4.Cu" signal)
		(12 "In5.Cu" power)
		(14 "In6.Cu" power)
		(16 "In7.Cu" signal)
		(18 "In8.Cu" power)
		(20 "In9.Cu" signal)
		(22 "In10.Cu" power)
		(24 "In11.Cu" signal)
		(26 "In12.Cu" signal)
		(2 "B.Cu" mixed)
		(9 "F.Adhes" user "F.Adhesive")
		(11 "B.Adhes" user "B.Adhesive")
		(13 "F.Paste" user)
		(15 "B.Paste" user)
		(5 "F.SilkS" user "F.Silkscreen")
		(7 "B.SilkS" user "B.Silkscreen")
		(1 "F.Mask" user)
		(3 "B.Mask" user)
		(17 "Dwgs.User" user "User.Drawings")
		(19 "Cmts.User" user "User.Comments")
		(21 "Eco1.User" user "User.Eco1")
		(23 "Eco2.User" user "User.Eco2")
		(25 "Edge.Cuts" user)
		(27 "Margin" user)
		(31 "F.CrtYd" user "F.Courtyard")
		(29 "B.CrtYd" user "B.Courtyard")
		(35 "F.Fab" user)
		(33 "B.Fab" user)
	)
	(footprint "antmicro-footprints:BGA-200_10.0x14.5mm_Layout12x22_P0.80x0.65mm"
		(layer "F.Cu")
		(at 180 129.6)
		(descr "BGA-200, 14.5x10.0mm, 200 Ball, 12x22 Layout, 0.8x0.65mm Pitch, http://www.issi.com/WW/pdf/43-46LQ32256A-AL.pdf")
		(tags "BGA 200 0.8x0.65")
		(property "Reference" "U12"
			(at 6.26 1.53 270)
			(layer "F.SilkS")
			(effects
				(font
					(size 0.7 0.7)
					(thickness 0.15)
				)
				(justify left bottom)
			)
		)
		(property "Value" "MT53D512M32D2_WFBGA"
			(at -5.5 9 0)
			(layer "F.Fab")
			(hide yes)
			(effects
				(font
					(size 0.7 0.7)
					(thickness 0.15)
				)
				(justify left bottom)
			)
		)
		(property "Datasheet" "https://eu.mouser.com/datasheet/2/671/200b_z11m_non_auto_lpddr4_lpddr4x-3077547.pdf"
			(at 0 0 0)
			(layer "F.Fab")
			(hide yes)
			(effects
				(font
					(size 1.27 1.27)
					(thickness 0.15)
				)
			)
		)
		(property "Description" "LPDDR4 DRAM, 1GX32"
			(at 0 0 0)
			(layer "F.Fab")
			(hide yes)
			(effects
				(font
					(size 1.27 1.27)
					(thickness 0.15)
				)
			)
		)
		(property "Author" "Antmicro"
			(at 0 0 0)
			(layer "F.Fab")
			(hide yes)
			(effects
				(font
					(size 1 1)
					(thickness 0.15)
				)
			)
		)
		(property "License" "Apache-2.0"
			(at 0 0 0)
			(layer "F.Fab")
			(hide yes)
			(effects
				(font
					(size 1 1)
					(thickness 0.15)
				)
			)
		)
		(property "MPN" "MT53D512M32D2DS-053 WT:D TR"
			(at 0 0 0)
			(layer "F.Fab")
			(hide yes)
			(effects
				(font
					(size 1 1)
					(thickness 0.15)
				)
			)
		)
		(property "Manufacturer" "Micron Technology"
			(at 0 0 0)
			(layer "F.Fab")
			(hide yes)
			(effects
				(font
					(size 1 1)
					(thickness 0.15)
				)
			)
		)
		(property "VSD_class" "LPDDR4"
			(at 0 0 0)
			(layer "F.Fab")
			(hide yes)
			(effects
				(font
					(size 1 1)
					(thickness 0.15)
				)
			)
		)
		(property ki_fp_filters "WFBGA200_10X14p5_DS_MRN WFBGA200_10X14p5_DS_MRN-M WFBGA200_10X14p5_DS_MRN-L")
		(sheetname "/LPDDR4/")
		(sheetfile "lpddr.kicad_sch")
		(attr smd)
		(pad "G3" smd circle
			(at -2.795 -2.934)
			(size 0.27 0.27)
			(layers "F.Cu" "F.Mask" "F.Paste")
			(net 417 "GND")
			(pinfunction "VSS")
			(pintype "passive")
		)
		(pad "G4" smd circle
			(at -1.996 -2.934)
			(size 0.27 0.27)
			(layers "F.Cu" "F.Mask" "F.Paste")
			(net 48 "+1V8")
			(pinfunction "VDD1")
			(pintype "passive")
		)
		(pad "G5" smd circle
			(at -1.196 -2.934)
			(size 0.27 0.27)
			(layers "F.Cu" "F.Mask" "F.Paste")
			(net 417 "GND")
			(pinfunction "VSS")
			(pintype "passive")
		)
		(pad "G8" smd circle
			(at 1.205 -2.934)
			(size 0.27 0.27)
			(layers "F.Cu" "F.Mask" "F.Paste")
			(net 417 "GND")
			(pinfunction "VSS")
			(pintype "passive")
		)
		(pad "G9" smd circle
			(at 2.004 -2.934)
			(size 0.27 0.27)
			(layers "F.Cu" "F.Mask" "F.Paste")
			(net 48 "+1V8")
			(pinfunction "VDD1")
			(pintype "passive")
		)
		(pad "G10" smd circle
			(at 2.805 -2.934)
			(size 0.27 0.27)
			(layers "F.Cu" "F.Mask" "F.Paste")
			(net 417 "GND")
			(pinfunction "VSS")
			(pintype "passive")
		)
		(pad "G11" smd circle
			(at 3.604 -2.934)
			(size 0.27 0.27)
			(layers "F.Cu" "F.Mask" "F.Paste")
			(net 491 "unconnected-(U12B-NC-PadG11)")
			(pinfunction "NC")
			(pintype "no_connect")
		)
		(pad "G12" smd circle
			(at 4.405 -2.934)
			(size 0.27 0.27)
			(layers "F.Cu" "F.Mask" "F.Paste")
			(net 417 "GND")
			(pinfunction "VSS")
			(pintype "passive")
		)
		(pad "H1" smd circle
			(at -4.396 -2.283)
			(size 0.27 0.27)
			(layers "F.Cu" "F.Mask" "F.Paste")
			(net 2 "+1V1")
			(pinfunction "VDD2")
			(pintype "passive")
		)
		(pad "H2" smd circle
			(at -3.596 -2.283)
			(size 0.27 0.27)
			(layers "F.Cu" "F.Mask" "F.Paste")
			(net 587 "/FPGA MSS/LPDDR4.CA0_A")
			(pinfunction "CA0_A")
			(pintype "input")
		)
		(pad "H3" smd circle
			(at -2.795 -2.283)
			(size 0.27 0.27)
			(layers "F.Cu" "F.Mask" "F.Paste")
			(net 492 "unconnected-(U12A-NC-PadH3)")
			(pinfunction "NC")
			(pintype "no_connect")
		)
		(pad "H4" smd circle
			(at -1.996 -2.283)
			(size 0.27 0.27)
			(layers "F.Cu" "F.Mask" "F.Paste")
			(net 395 "/FPGA MSS/LPDDR4.CS0_A")
			(pinfunction "CS0_A")
			(pintype "input")
		)
		(pad "H5" smd circle
			(at -1.196 -2.283)
			(size 0.27 0.27)
			(layers "F.Cu" "F.Mask" "F.Paste")
			(net 2 "+1V1")
			(pinfunction "VDD2")
			(pintype "passive")
		)
		(pad "H8" smd circle
			(at 1.205 -2.283)
			(size 0.27 0.27)
			(layers "F.Cu" "F.Mask" "F.Paste")
			(net 2 "+1V1")
			(pinfunction "VDD2")
			(pintype "passive")
		)
		(pad "H9" smd circle
			(at 2.004 -2.283)
			(size 0.27 0.27)
			(layers "F.Cu" "F.Mask" "F.Paste")
			(net 598 "/FPGA MSS/LPDDR4.CA2_A")
			(pinfunction "CA2_A")
			(pintype "input")
		)
		(pad "H10" smd circle
			(at 2.805 -2.283)
			(size 0.27 0.27)
			(layers "F.Cu" "F.Mask" "F.Paste")
			(net 597 "/FPGA MSS/LPDDR4.CA3_A")
			(pinfunction "CA3_A")
			(pintype "input")
		)
		(pad "H11" smd circle
			(at 3.604 -2.283)
			(size 0.27 0.27)
			(layers "F.Cu" "F.Mask" "F.Paste")
			(net 583 "/FPGA MSS/LPDDR4.CA4_A")
			(pinfunction "CA4_A")
			(pintype "input")
		)
		(pad "H12" smd circle
			(at 4.405 -2.283)
			(size 0.27 0.27)
			(layers "F.Cu" "F.Mask" "F.Paste")
			(net 2 "+1V1")
			(pinfunction "VDD2")
			(pintype "passive")
		)
		(pad "J1" smd circle
			(at -4.396 -1.633)
			(size 0.27 0.27)
			(layers "F.Cu" "F.Mask" "F.Paste")
			(net 417 "GND")
			(pinfunction "VSS")
			(pintype "passive")
		)
		(pad "J2" smd circle
			(at -3.596 -1.633)
			(size 0.27 0.27)
			(layers "F.Cu" "F.Mask" "F.Paste")
			(net 588 "/FPGA MSS/LPDDR4.CA1_A")
			(pinfunction "CA1_A")
			(pintype "input")
		)
		(pad "J3" smd circle
			(at -2.795 -1.633)
			(size 0.27 0.27)
			(layers "F.Cu" "F.Mask" "F.Paste")
			(net 417 "GND")
			(pinfunction "VSS")
			(pintype "passive")
		)
		(pad "J4" smd circle
			(at -1.996 -1.633)
			(size 0.27 0.27)
			(layers "F.Cu" "F.Mask" "F.Paste")
			(net 389 "/FPGA MSS/LPDDR4.CKE0_A")
			(pinfunction "CKE0_A")
			(pintype "input")
		)
		(pad "J5" smd circle
			(at -1.196 -1.633)
			(size 0.27 0.27)
			(layers "F.Cu" "F.Mask" "F.Paste")
			(net 536 "unconnected-(U12A-NC-PadJ5)")
			(pinfunction "NC")
			(pintype "no_connect")
		)
		(pad "J8" smd circle
			(at 1.205 -1.633)
			(size 0.27 0.27)
			(layers "F.Cu" "F.Mask" "F.Paste")
			(net 593 "/FPGA MSS/LPDDR4.CK_P")
			(pinfunction "CK_t_A")
			(pintype "input")
		)
		(pad "J9" smd circle
			(at 2.004 -1.633)
			(size 0.27 0.27)
			(layers "F.Cu" "F.Mask" "F.Paste")
			(net 592 "/FPGA MSS/LPDDR4.CK_N")
			(pinfunction "CK_c_A")
			(pintype "input")
		)
		(pad "J10" smd circle
			(at 2.805 -1.633)
			(size 0.27 0.27)
			(layers "F.Cu" "F.Mask" "F.Paste")
			(net 417 "GND")
			(pinfunction "VSS")
			(pintype "passive")
		)
		(pad "J11" smd circle
			(at 3.604 -1.633)
			(size 0.27 0.27)
			(layers "F.Cu" "F.Mask" "F.Paste")
			(net 568 "/FPGA MSS/LPDDR4.CA5_A")
			(pinfunction "CA5_A")
			(pintype "input")
		)
		(pad "J12" smd circle
			(at 4.405 -1.633)
			(size 0.27 0.27)
			(layers "F.Cu" "F.Mask" "F.Paste")
			(net 417 "GND")
			(pinfunction "VSS")
			(pintype "passive")
		)
		(pad "K1" smd circle
			(at -4.396 -0.983)
			(size 0.27 0.27)
			(layers "F.Cu" "F.Mask" "F.Paste")
			(net 2 "+1V1")
			(pinfunction "VDD2")
			(pintype "passive")
		)
		(pad "K2" smd circle
			(at -3.596 -0.983)
			(size 0.27 0.27)
			(layers "F.Cu" "F.Mask" "F.Paste")
			(net 417 "GND")
			(pinfunction "VSS")
			(pintype "passive")
		)
		(pad "K3" smd circle
			(at -2.795 -0.983)
			(size 0.27 0.27)
			(layers "F.Cu" "F.Mask" "F.Paste")
			(net 2 "+1V1")
			(pinfunction "VDD2")
			(pintype "passive")
		)
		(pad "K4" smd circle
			(at -1.996 -0.983)
			(size 0.27 0.27)
			(layers "F.Cu" "F.Mask" "F.Paste")
			(net 417 "GND")
			(pinfunction "VSS")
			(pintype "passive")
		)
		(pad "K5" smd circle
			(at -1.196 -0.983)
			(size 0.27 0.27)
			(layers "F.Cu" "F.Mask" "F.Paste")
			(net 493 "unconnected-(U12A-NC-PadK5)")
			(pinfunction "NC")
			(pintype "no_connect")
		)
		(pad "K8" smd circle
			(at 1.205 -0.983)
			(size 0.27 0.27)
			(layers "F.Cu" "F.Mask" "F.Paste")
			(net 494 "unconnected-(U12A-NC-PadK8)")
			(pinfunction "NC")
			(pintype "no_connect")
		)
		(pad "K9" smd circle
			(at 2.004 -0.983)
			(size 0.27 0.27)
			(layers "F.Cu" "F.Mask" "F.Paste")
			(net 417 "GND")
			(pinfunction "VSS")
			(pintype "passive")
		)
		(pad "K10" smd circle
			(at 2.805 -0.983)
			(size 0.27 0.27)
			(layers "F.Cu" "F.Mask" "F.Paste")
			(net 2 "+1V1")
			(pinfunction "VDD2")
			(pintype "passive")
		)
		(pad "K11" smd circle
			(at 3.604 -0.983)
			(size 0.27 0.27)
			(layers "F.Cu" "F.Mask" "F.Paste")
			(net 417 "GND")
			(pinfunction "VSS")
			(pintype "passive")
		)
		(pad "K12" smd circle
			(at 4.405 -0.983)
			(size 0.27 0.27)
			(layers "F.Cu" "F.Mask" "F.Paste")
			(net 2 "+1V1")
			(pinfunction "VDD2")
			(pintype "passive")
		)
		(pad "N1" smd circle
			(at -4.396 0.966)
			(size 0.27 0.27)
			(layers "F.Cu" "F.Mask" "F.Paste")
			(net 2 "+1V1")
			(pinfunction "VDD2")
			(pintype "passive")
		)
		(pad "N2" smd circle
			(at -3.596 0.966)
			(size 0.27 0.27)
			(layers "F.Cu" "F.Mask" "F.Paste")
			(net 417 "GND")
			(pinfunction "VSS")
			(pintype "passive")
		)
		(pad "N3" smd circle
			(at -2.795 0.966)
			(size 0.27 0.27)
			(layers "F.Cu" "F.Mask" "F.Paste")
			(net 2 "+1V1")
			(pinfunction "VDD2")
			(pintype "passive")
		)
		(pad "N4" smd circle
			(at -1.996 0.966)
			(size 0.27 0.27)
			(layers "F.Cu" "F.Mask" "F.Paste")
			(net 417 "GND")
			(pinfunction "VSS")
			(pintype "passive")
		)
		(pad "N5" smd circle
			(at -1.196 0.966)
			(size 0.27 0.27)
			(layers "F.Cu" "F.Mask" "F.Paste")
			(net 495 "unconnected-(U12A-NC-PadN5)")
			(pinfunction "NC")
			(pintype "no_connect")
		)
		(pad "N8" smd circle
			(at 1.205 0.966)
			(size 0.27 0.27)
			(layers "F.Cu" "F.Mask" "F.Paste")
			(net 496 "unconnected-(U12A-NC-PadN8)")
			(pinfunction "NC")
			(pintype "no_connect")
		)
		(pad "N9" smd circle
			(at 2.004 0.966)
			(size 0.27 0.27)
			(layers "F.Cu" "F.Mask" "F.Paste")
			(net 417 "GND")
			(pinfunction "VSS")
			(pintype "passive")
		)
		(pad "N10" smd circle
			(at 2.805 0.966)
			(size 0.27 0.27)
			(layers "F.Cu" "F.Mask" "F.Paste")
			(net 2 "+1V1")
			(pinfunction "VDD2")
			(pintype "passive")
		)
		(pad "N11" smd circle
			(at 3.604 0.966)
			(size 0.27 0.27)
			(layers "F.Cu" "F.Mask" "F.Paste")
			(net 417 "GND")
			(pinfunction "VSS")
			(pintype "passive")
		)
		(pad "N12" smd circle
			(at 4.405 0.966)
			(size 0.27 0.27)
			(layers "F.Cu" "F.Mask" "F.Paste")
			(net 2 "+1V1")
			(pinfunction "VDD2")
			(pintype "passive")
		)
		(pad "P1" smd circle
			(at -4.396 1.616)
			(size 0.27 0.27)
			(layers "F.Cu" "F.Mask" "F.Paste")
			(net 417 "GND")
			(pinfunction "VSS")
			(pintype "passive")
		)
		(pad "P2" smd circle
			(at -3.596 1.616)
			(size 0.27 0.27)
			(layers "F.Cu" "F.Mask" "F.Paste")
			(net 588 "/FPGA MSS/LPDDR4.CA1_A")
			(pinfunction "CA1_B")
			(pintype "input")
		)
		(pad "P3" smd circle
			(at -2.795 1.616)
			(size 0.27 0.27)
			(layers "F.Cu" "F.Mask" "F.Paste")
			(net 417 "GND")
			(pinfunction "VSS")
			(pintype "passive")
		)
		(pad "P4" smd circle
			(at -1.996 1.616)
			(size 0.27 0.27)
			(layers "F.Cu" "F.Mask" "F.Paste")
			(net 389 "/FPGA MSS/LPDDR4.CKE0_A")
			(pinfunction "CKE0_B")
			(pintype "input")
		)
		(pad "P5" smd circle
			(at -1.196 1.616)
			(size 0.27 0.27)
			(layers "F.Cu" "F.Mask" "F.Paste")
			(net 535 "unconnected-(U12A-NC-PadP5)")
			(pinfunction "NC")
			(pintype "no_connect")
		)
		(pad "P8" smd circle
			(at 1.205 1.616)
			(size 0.27 0.27)
			(layers "F.Cu" "F.Mask" "F.Paste")
			(net 593 "/FPGA MSS/LPDDR4.CK_P")
			(pinfunction "CK_t_B")
			(pintype "input")
		)
		(pad "P9" smd circle
			(at 2.004 1.616)
			(size 0.27 0.27)
			(layers "F.Cu" "F.Mask" "F.Paste")
			(net 592 "/FPGA MSS/LPDDR4.CK_N")
			(pinfunction "CK_c_B")
			(pintype "input")
		)
		(pad "P10" smd circle
			(at 2.805 1.616)
			(size 0.27 0.27)
			(layers "F.Cu" "F.Mask" "F.Paste")
			(net 417 "GND")
			(pinfunction "VSS")
			(pintype "passive")
		)
		(pad "P11" smd circle
			(at 3.604 1.616)
			(size 0.27 0.27)
			(layers "F.Cu" "F.Mask" "F.Paste")
			(net 568 "/FPGA MSS/LPDDR4.CA5_A")
			(pinfunction "CA5_B")
			(pintype "input")
		)
		(pad "P12" smd circle
			(at 4.405 1.616)
			(size 0.27 0.27)
			(layers "F.Cu" "F.Mask" "F.Paste")
			(net 417 "GND")
			(pinfunction "VSS")
			(pintype "passive")
		)
		(pad "R1" smd circle
			(at -4.396 2.266)
			(size 0.27 0.27)
			(layers "F.Cu" "F.Mask" "F.Paste")
			(net 2 "+1V1")
			(pinfunction "VDD2")
			(pintype "passive")
		)
		(pad "R2" smd circle
			(at -3.596 2.266)
			(size 0.27 0.27)
			(layers "F.Cu" "F.Mask" "F.Paste")
			(net 587 "/FPGA MSS/LPDDR4.CA0_A")
			(pinfunction "CA0_B")
			(pintype "input")
		)
		(pad "R3" smd circle
			(at -2.795 2.266)
			(size 0.27 0.27)
			(layers "F.Cu" "F.Mask" "F.Paste")
			(net 497 "unconnected-(U12A-NC-PadR3)")
			(pinfunction "NC")
			(pintype "no_connect")
		)
		(pad "R4" smd circle
			(at -1.996 2.266)
			(size 0.27 0.27)
			(layers "F.Cu" "F.Mask" "F.Paste")
			(net 395 "/FPGA MSS/LPDDR4.CS0_A")
			(pinfunction "CS0_B")
			(pintype "input")
		)
		(pad "R5" smd circle
			(at -1.196 2.266)
			(size 0.27 0.27)
			(layers "F.Cu" "F.Mask" "F.Paste")
			(net 2 "+1V1")
			(pinfunction "VDD2")
			(pintype "passive")
		)
		(pad "R8" smd circle
			(at 1.205 2.266)
			(size 0.27 0.27)
			(layers "F.Cu" "F.Mask" "F.Paste")
			(net 2 "+1V1")
			(pinfunction "VDD2")
			(pintype "passive")
		)
		(pad "R9" smd circle
			(at 2.004 2.266)
			(size 0.27 0.27)
			(layers "F.Cu" "F.Mask" "F.Paste")
			(net 598 "/FPGA MSS/LPDDR4.CA2_A")
			(pinfunction "CA2_B")
			(pintype "input")
		)
		(pad "R10" smd circle
			(at 2.805 2.266)
			(size 0.27 0.27)
			(layers "F.Cu" "F.Mask" "F.Paste")
			(net 597 "/FPGA MSS/LPDDR4.CA3_A")
			(pinfunction "CA3_B")
			(pintype "input")
		)
		(pad "R11" smd circle
			(at 3.604 2.266)
			(size 0.27 0.27)
			(layers "F.Cu" "F.Mask" "F.Paste")
			(net 583 "/FPGA MSS/LPDDR4.CA4_A")
			(pinfunction "CA4_B")
			(pintype "input")
		)
		(pad "R12" smd circle
			(at 4.405 2.266)
			(size 0.27 0.27)
			(layers "F.Cu" "F.Mask" "F.Paste")
			(net 2 "+1V1")
			(pinfunction "VDD2")
			(pintype "passive")
		)
		(pad "T1" smd circle
			(at -4.396 2.917)
			(size 0.27 0.27)
			(layers "F.Cu" "F.Mask" "F.Paste")
			(net 417 "GND")
			(pinfunction "VSS")
			(pintype "passive")
		)
		(pad "T2" smd circle
			(at -3.596 2.917)
			(size 0.27 0.27)
			(layers "F.Cu" "F.Mask" "F.Paste")
			(net 393 "/FPGA MSS/LPDDR4.ODT_CA_A")
			(pinfunction "ODT_CA_B")
			(pintype "input")
		)
		(pad "T3" smd circle
			(at -2.795 2.917)
			(size 0.27 0.27)
			(layers "F.Cu" "F.Mask" "F.Paste")
			(net 417 "GND")
			(pinfunction "VSS")
			(pintype "passive")
		)
		(pad "T4" smd circle
			(at -1.996 2.917)
			(size 0.27 0.27)
			(layers "F.Cu" "F.Mask" "F.Paste")
			(net 48 "+1V8")
			(pinfunction "VDD1")
			(pintype "passive")
		)
		(pad "T5" smd circle
			(at -1.196 2.917)
			(size 0.27 0.27)
			(layers "F.Cu" "F.Mask" "F.Paste")
			(net 417 "GND")
			(pinfunction "VSS")
			(pintype "passive")
		)
		(pad "T8" smd circle
			(at 1.205 2.917)
			(size 0.27 0.27)
			(layers "F.Cu" "F.Mask" "F.Paste")
			(net 417 "GND")
			(pinfunction "VSS")
			(pintype "passive")
		)
		(pad "T9" smd circle
			(at 2.004 2.917)
			(size 0.27 0.27)
			(layers "F.Cu" "F.Mask" "F.Paste")
			(net 48 "+1V8")
			(pinfunction "VDD1")
			(pintype "passive")
		)
		(pad "T10" smd circle
			(at 2.805 2.917)
			(size 0.27 0.27)
			(layers "F.Cu" "F.Mask" "F.Paste")
			(net 417 "GND")
			(pinfunction "VSS")
			(pintype "passive")
		)
		(pad "T11" smd circle
			(at 3.604 2.917)
			(size 0.27 0.27)
			(layers "F.Cu" "F.Mask" "F.Paste")
			(net 394 "/FPGA MSS/LPDDR4.RESET_n")
			(pinfunction "RESET_n")
			(pintype "input")
		)
		(pad "T12" smd circle
			(at 4.405 2.917)
			(size 0.27 0.27)
			(layers "F.Cu" "F.Mask" "F.Paste")
			(net 417 "GND")
			(pinfunction "VSS")
			(pintype "passive")
		)
		(pad "U1" smd circle
			(at -4.396 3.567)
			(size 0.27 0.27)
			(layers "F.Cu" "F.Mask" "F.Paste")
			(net 48 "+1V8")
			(pinfunction "VDD1")
			(pintype "passive")
		)
		(pad "U2" smd circle
			(at -3.596 3.567)
			(size 0.27 0.27)
			(layers "F.Cu" "F.Mask" "F.Paste")
			(net 326 "/FPGA MSS/LPDDR4.DQ19")
			(pinfunction "DQ3_B")
			(pintype "bidirectional")
		)
		(pad "U3" smd circle
			(at -2.795 3.567)
			(size 0.27 0.27)
			(layers "F.Cu" "F.Mask" "F.Paste")
			(net 2 "+1V1")
			(pinfunction "VDDQ")
			(pintype "passive")
		)
		(pad "U4" smd circle
			(at -1.996 3.567)
			(size 0.27 0.27)
			(layers "F.Cu" "F.Mask" "F.Paste")
			(net 601 "/FPGA MSS/LPDDR4.DQ20")
			(pinfunction "DQ4_B")
			(pintype "bidirectional")
		)
		(pad "U5" smd circle
			(at -1.196 3.567)
			(size 0.27 0.27)
			(layers "F.Cu" "F.Mask" "F.Paste")
			(net 2 "+1V1")
			(pinfunction "VDD2")
			(pintype "passive")
		)
		(pad "U8" smd circle
			(at 1.205 3.567)
			(size 0.27 0.27)
			(layers "F.Cu" "F.Mask" "F.Paste")
			(net 2 "+1V1")
			(pinfunction "VDD2")
			(pintype "passive")
		)
		(pad "U9" smd circle
			(at 2.004 3.567)
			(size 0.27 0.27)
			(layers "F.Cu" "F.Mask" "F.Paste")
			(net 586 "/FPGA MSS/LPDDR4.DQ28")
			(pinfunction "DQ12_B")
			(pintype "bidirectional")
		)
	)
)
